FILE_TYPE = MULTI_PHYS_TABLE;

PART '9SQ440NQQI8'

{========================================================================================}
:VALUE         | PART_TYPE | MATERIAL | PART_NUMBER    = STANDARD        | LIFECYCLE          | PART_NUMBER   | JEDEC_TYPE          | DESCRIPTION                      | MANUFTR | MANUF_PN      | RD_CMPLS_LVL | CMPLS_LVL | FROM_PJ     | CLASS | DIP_SMD | DATA                  | EE_CHECK_LIST | FP_ECN | PSL | CREATOR | STATUS | MSD  | ESD_CDM | ESD_HBM | ESD_MM | PIN_LENGTH_SHORT_PIN | PIN_LENGTH_LONG_PIN | CREATEDAY  ;
{========================================================================================}
 '9SQ440NQQI8' | 'SMLF'    | 'IC'     | 'AJ004400000'(!) = ''               | ''               | 'AJ004400000' |'QFN100_TH_0-5_8X8'| 'IC OTHER(100P)9SQ440NQQI8(QFN)' | 'IDT'   | '9SQ440NQQI8' | 'EP(V1)'     | ''        | 'S6X-SANDY' | 'IC'  | ''      | 'IDT_9SQ440NQQI8.pdf' | ''            | ''     | ''  | ''      | ''     | 'NA' | 'N/A'   | 'N/A'   | 'N/A'  | '0 MILS'             | '0 MILS'            | '20191205'
 '9SQ440NQQI8' | 'SMLF'    | 'EMPTY'  | 'AJ004400000'(!) = ''               | ''               | 'AJ004400000' |'QFN100_TH_0-5_8X8'| 'IC OTHER(100P)9SQ440NQQI8(QFN)' | 'IDT'   | '9SQ440NQQI8' | 'EP(V1)'     | ''        | 'S6X-SANDY' | 'IC'  | ''      | 'IDT_9SQ440NQQI8.pdf' | ''            | ''     | ''  | ''      | ''     | 'NA' | 'N/A'   | 'N/A'   | 'N/A'  | '0 MILS'             | '0 MILS'            | '20191205'

END_PART

END.

